(kicad_pcb
	(version 20260206)
	(generator "pcbnew")
	(generator_version "10.0")
	(general
		(thickness 1.6)
		(legacy_teardrops no)
	)
	(paper "A4")
	(title_block
		(title "04192023_DAF0TMB3IC0_F0TG_MB_C_brd_V02_OCP.brd")
		(comment 1 "Grand Teton / footprints 2745-2752 of 8354")
	)
	(layers
		(0 "F.Cu" signal "TOP")
		(4 "In1.Cu" signal "GND")
		(6 "In2.Cu" signal "IN1")
		(8 "In3.Cu" signal "GND1")
		(10 "In4.Cu" signal "IN2")
		(12 "In5.Cu" signal "GND2")
		(14 "In6.Cu" signal "IN3")
		(16 "In7.Cu" signal "GND3")
		(18 "In8.Cu" signal "VCC")
		(20 "In9.Cu" signal "VCC1")
		(22 "In10.Cu" signal "GND4")
		(24 "In11.Cu" signal "IN4")
		(26 "In12.Cu" signal "GND5")
		(28 "In13.Cu" signal "IN5")
		(30 "In14.Cu" signal "GND6")
		(32 "In15.Cu" signal "IN6")
		(34 "In16.Cu" signal "GND7")
		(2 "B.Cu" signal "BOTTOM")
		(9 "F.Adhes" user "F.Adhesive")
		(11 "B.Adhes" user "B.Adhesive")
		(13 "F.Paste" user "Package Geometry/Pastemask Top")
		(15 "B.Paste" user "Package Geometry/Pastemask Bottom")
		(5 "F.SilkS" user "Ref Des/Silkscreen Top")
		(7 "B.SilkS" user "Ref Des/Silkscreen Bottom")
		(1 "F.Mask" user "Board Geometry/Soldermask Top")
		(3 "B.Mask" user "Board Geometry/Soldermask Bottom")
		(17 "Dwgs.User" user "User.Drawings")
		(19 "Cmts.User" user "User.Comments")
		(21 "Eco1.User" user "User.Eco1")
		(23 "Eco2.User" user "User.Eco2")
		(25 "Edge.Cuts" user "Board Geometry/Outline")
		(27 "Margin" user)
		(31 "F.CrtYd" user "Package Geometry/Place Bound Top")
		(29 "B.CrtYd" user "Package Geometry/Place Bound Bottom")
		(35 "F.Fab" user "Ref Des/Assembly Top")
		(33 "B.Fab" user "Ref Des/Assembly Bottom")
	)
	(footprint ""
		(layer "F.Cu")
		(at 100.48367 -408.183588 180)
		(property "Reference" "C90"
			(at 0 0 180)
			(layer "F.SilkS")
			(hide yes)
			(effects
				(font
					(size 1.27 1.27)
				)
			)
		)
		(property "Value" ""
			(at 0 0 180)
			(layer "F.Fab")
			(effects
				(font
					(size 1.27 1.27)
				)
			)
		)
		(duplicate_pad_numbers_are_jumpers no)
		(fp_line
			(start 0.7874 0.4064)
			(end -0.7874 0.4064)
			(stroke
				(width 0.1524)
				(type default)
			)
			(layer "F.SilkS")
		)
		(fp_line
			(start 0.7874 -0.4064)
			(end 0.7874 0.4064)
			(stroke
				(width 0.1524)
				(type default)
			)
			(layer "F.SilkS")
		)
		(fp_line
			(start -0.7874 0.4064)
			(end -0.7874 -0.4064)
			(stroke
				(width 0.1524)
				(type default)
			)
			(layer "F.SilkS")
		)
		(fp_line
			(start -0.7874 -0.4064)
			(end 0.7874 -0.4064)
			(stroke
				(width 0.1524)
				(type default)
			)
			(layer "F.SilkS")
		)
		(fp_line
			(start 0.67945 0.3048)
			(end 0.120396 0.3048)
			(stroke
				(width 0.1)
				(type default)
			)
			(layer "F.Fab")
		)
		(fp_line
			(start 0.67945 -0.3048)
			(end 0.67945 0.3048)
			(stroke
				(width 0.1)
				(type default)
			)
			(layer "F.Fab")
		)
		(fp_line
			(start 0.12065 -0.2794)
			(end 0.12065 -0.3048)
			(stroke
				(width 0.1)
				(type default)
			)
			(layer "F.Fab")
		)
		(fp_line
			(start 0.12065 -0.3048)
			(end 0.67945 -0.3048)
			(stroke
				(width 0.1)
				(type default)
			)
			(layer "F.Fab")
		)
		(fp_line
			(start 0.120396 0.3048)
			(end 0.120396 0.2794)
			(stroke
				(width 0.1)
				(type default)
			)
			(layer "F.Fab")
		)
		(fp_line
			(start 0.120396 0.2794)
			(end -0.12065 0.2794)
			(stroke
				(width 0.1)
				(type default)
			)
			(layer "F.Fab")
		)
		(fp_line
			(start -0.12065 0.3048)
			(end -0.67945 0.3048)
			(stroke
				(width 0.1)
				(type default)
			)
			(layer "F.Fab")
		)
		(fp_line
			(start -0.12065 0.2794)
			(end -0.12065 0.3048)
			(stroke
				(width 0.1)
				(type default)
			)
			(layer "F.Fab")
		)
		(fp_line
			(start -0.12065 -0.2794)
			(end 0.12065 -0.2794)
			(stroke
				(width 0.1)
				(type default)
			)
			(layer "F.Fab")
		)
		(fp_line
			(start -0.12065 -0.305054)
			(end -0.12065 -0.2794)
			(stroke
				(width 0.1)
				(type default)
			)
			(layer "F.Fab")
		)
		(fp_line
			(start -0.67945 0.3048)
			(end -0.67945 -0.305054)
			(stroke
				(width 0.1)
				(type default)
			)
			(layer "F.Fab")
		)
		(fp_line
			(start -0.67945 -0.305054)
			(end -0.12065 -0.305054)
			(stroke
				(width 0.1)
				(type default)
			)
			(layer "F.Fab")
		)
		(pad "1" smd circle
			(at -0.40005 0 180)
			(size 0 0)
			(layers "F.Cu" "F.Mask" "F.Paste")
			(net "P3V3_9ZXL045_P1_VDD")
		)
		(pad "2" smd circle
			(at 0.40005 0 180)
			(size 0 0)
			(layers "F.Cu" "F.Mask" "F.Paste")
			(net "GND")
		)
	)
	(footprint ""
		(layer "F.Cu")
		(at 24.765 -358.775)
		(property "Reference" "R8238"
			(at 0 0 0)
			(layer "F.SilkS")
			(hide yes)
			(effects
				(font
					(size 1.27 1.27)
				)
			)
		)
		(property "Value" ""
			(at 0 0 0)
			(layer "F.Fab")
			(effects
				(font
					(size 1.27 1.27)
				)
			)
		)
		(duplicate_pad_numbers_are_jumpers no)
		(fp_line
			(start -0.7874 -0.4064)
			(end 0.7874 -0.4064)
			(stroke
				(width 0.1524)
				(type default)
			)
			(layer "F.SilkS")
		)
		(fp_line
			(start -0.7874 0.4064)
			(end -0.7874 -0.4064)
			(stroke
				(width 0.1524)
				(type default)
			)
			(layer "F.SilkS")
		)
		(fp_line
			(start 0.7874 -0.4064)
			(end 0.7874 0.4064)
			(stroke
				(width 0.1524)
				(type default)
			)
			(layer "F.SilkS")
		)
		(fp_line
			(start 0.7874 0.4064)
			(end -0.7874 0.4064)
			(stroke
				(width 0.1524)
				(type default)
			)
			(layer "F.SilkS")
		)
		(fp_line
			(start -0.67945 -0.305054)
			(end -0.12065 -0.305054)
			(stroke
				(width 0.1)
				(type default)
			)
			(layer "F.Fab")
		)
		(fp_line
			(start -0.67945 0.3048)
			(end -0.67945 -0.305054)
			(stroke
				(width 0.1)
				(type default)
			)
			(layer "F.Fab")
		)
		(fp_line
			(start -0.12065 -0.305054)
			(end -0.12065 -0.2794)
			(stroke
				(width 0.1)
				(type default)
			)
			(layer "F.Fab")
		)
		(fp_line
			(start -0.12065 -0.2794)
			(end 0.12065 -0.2794)
			(stroke
				(width 0.1)
				(type default)
			)
			(layer "F.Fab")
		)
		(fp_line
			(start -0.12065 0.2794)
			(end -0.12065 0.3048)
			(stroke
				(width 0.1)
				(type default)
			)
			(layer "F.Fab")
		)
		(fp_line
			(start -0.12065 0.3048)
			(end -0.67945 0.3048)
			(stroke
				(width 0.1)
				(type default)
			)
			(layer "F.Fab")
		)
		(fp_line
			(start 0.120396 0.2794)
			(end -0.12065 0.2794)
			(stroke
				(width 0.1)
				(type default)
			)
			(layer "F.Fab")
		)
		(fp_line
			(start 0.120396 0.3048)
			(end 0.120396 0.2794)
			(stroke
				(width 0.1)
				(type default)
			)
			(layer "F.Fab")
		)
		(fp_line
			(start 0.12065 -0.3048)
			(end 0.67945 -0.3048)
			(stroke
				(width 0.1)
				(type default)
			)
			(layer "F.Fab")
		)
		(fp_line
			(start 0.12065 -0.2794)
			(end 0.12065 -0.3048)
			(stroke
				(width 0.1)
				(type default)
			)
			(layer "F.Fab")
		)
		(fp_line
			(start 0.67945 -0.3048)
			(end 0.67945 0.3048)
			(stroke
				(width 0.1)
				(type default)
			)
			(layer "F.Fab")
		)
		(fp_line
			(start 0.67945 0.3048)
			(end 0.120396 0.3048)
			(stroke
				(width 0.1)
				(type default)
			)
			(layer "F.Fab")
		)
		(pad "1" smd circle
			(at -0.40005 0)
			(size 0 0)
			(layers "F.Cu" "F.Mask" "F.Paste")
			(net "SVID_PVDDCR_CPU1_P1_SVTO")
		)
		(pad "2" smd circle
			(at 0.40005 0)
			(size 0 0)
			(layers "F.Cu" "F.Mask" "F.Paste")
			(net "SVID_PVDDCR_CPU1_P1_SVTO_R")
		)
	)
	(footprint ""
		(layer "F.Cu")
		(at 90.654124 -408.517344 -90)
		(property "Reference" "C6658"
			(at 0 0 270)
			(layer "F.SilkS")
			(hide yes)
			(effects
				(font
					(size 1.27 1.27)
				)
			)
		)
		(property "Value" ""
			(at 0 0 270)
			(layer "F.Fab")
			(effects
				(font
					(size 1.27 1.27)
				)
			)
		)
		(duplicate_pad_numbers_are_jumpers no)
		(fp_line
			(start -0.299974 0.150114)
			(end -0.299974 -0.150114)
			(stroke
				(width 0.1)
				(type default)
			)
			(layer "F.Fab")
		)
		(fp_line
			(start 0.299974 0.150114)
			(end -0.299974 0.150114)
			(stroke
				(width 0.1)
				(type default)
			)
			(layer "F.Fab")
		)
		(fp_line
			(start -0.299974 -0.150114)
			(end 0.299974 -0.150114)
			(stroke
				(width 0.1)
				(type default)
			)
			(layer "F.Fab")
		)
		(fp_line
			(start 0.299974 -0.150114)
			(end 0.299974 0.150114)
			(stroke
				(width 0.1)
				(type default)
			)
			(layer "F.Fab")
		)
		(pad "1" smd rect
			(at -0.2667 0 270)
			(size 0.3048 0.381)
			(layers "F.Cu" "F.Mask" "F.Paste")
			(net "P5E_CPU1_P0_TX_BUF_C_DN<14>")
		)
		(pad "2" smd rect
			(at 0.2667 0 270)
			(size 0.3048 0.381)
			(layers "F.Cu" "F.Mask" "F.Paste")
			(net "P5E_CPU1_P0_TX_BUF_DN<14>")
		)
	)
	(footprint ""
		(layer "F.Cu")
		(at 100.332286 -402.917406 -90)
		(property "Reference" "R1201"
			(at 0 0 270)
			(layer "F.SilkS")
			(hide yes)
			(effects
				(font
					(size 1.27 1.27)
				)
			)
		)
		(property "Value" ""
			(at 0 0 270)
			(layer "F.Fab")
			(effects
				(font
					(size 1.27 1.27)
				)
			)
		)
		(duplicate_pad_numbers_are_jumpers no)
		(fp_line
			(start -0.32512 0.175006)
			(end -0.32512 -0.175006)
			(stroke
				(width 0.1)
				(type default)
			)
			(layer "F.Fab")
		)
		(fp_line
			(start 0.32512 0.175006)
			(end -0.32512 0.175006)
			(stroke
				(width 0.1)
				(type default)
			)
			(layer "F.Fab")
		)
		(fp_line
			(start -0.32512 -0.175006)
			(end 0.32512 -0.175006)
			(stroke
				(width 0.1)
				(type default)
			)
			(layer "F.Fab")
		)
		(fp_line
			(start 0.32512 -0.175006)
			(end 0.32512 0.175006)
			(stroke
				(width 0.1)
				(type default)
			)
			(layer "F.Fab")
		)
		(pad "1" smd rect
			(at -0.2667 0 270)
			(size 0.3048 0.381)
			(layers "F.Cu" "F.Mask" "F.Paste")
			(net "RST_SMB_RT_ROM_R1_N")
		)
		(pad "2" smd rect
			(at 0.2667 0 90)
			(size 0.3048 0.381)
			(layers "F.Cu" "F.Mask" "F.Paste")
			(net "FM_SMB_RT_ROM_MUX1_SEL")
		)
	)
	(footprint ""
		(layer "F.Cu")
		(at 213.061804 -22.974554 180)
		(property "Reference" "R1140"
			(at 0 0 180)
			(layer "F.SilkS")
			(hide yes)
			(effects
				(font
					(size 1.27 1.27)
				)
			)
		)
		(property "Value" ""
			(at 0 0 180)
			(layer "F.Fab")
			(effects
				(font
					(size 1.27 1.27)
				)
			)
		)
		(duplicate_pad_numbers_are_jumpers no)
		(fp_line
			(start 0.7874 0.4064)
			(end -0.7874 0.4064)
			(stroke
				(width 0.1524)
				(type default)
			)
			(layer "F.SilkS")
		)
		(fp_line
			(start 0.7874 -0.4064)
			(end 0.7874 0.4064)
			(stroke
				(width 0.1524)
				(type default)
			)
			(layer "F.SilkS")
		)
		(fp_line
			(start -0.7874 0.4064)
			(end -0.7874 -0.4064)
			(stroke
				(width 0.1524)
				(type default)
			)
			(layer "F.SilkS")
		)
		(fp_line
			(start -0.7874 -0.4064)
			(end 0.7874 -0.4064)
			(stroke
				(width 0.1524)
				(type default)
			)
			(layer "F.SilkS")
		)
		(fp_line
			(start 0.67945 0.3048)
			(end 0.120396 0.3048)
			(stroke
				(width 0.1)
				(type default)
			)
			(layer "F.Fab")
		)
		(fp_line
			(start 0.67945 -0.3048)
			(end 0.67945 0.3048)
			(stroke
				(width 0.1)
				(type default)
			)
			(layer "F.Fab")
		)
		(fp_line
			(start 0.12065 -0.2794)
			(end 0.12065 -0.3048)
			(stroke
				(width 0.1)
				(type default)
			)
			(layer "F.Fab")
		)
		(fp_line
			(start 0.12065 -0.3048)
			(end 0.67945 -0.3048)
			(stroke
				(width 0.1)
				(type default)
			)
			(layer "F.Fab")
		)
		(fp_line
			(start 0.120396 0.3048)
			(end 0.120396 0.2794)
			(stroke
				(width 0.1)
				(type default)
			)
			(layer "F.Fab")
		)
		(fp_line
			(start 0.120396 0.2794)
			(end -0.12065 0.2794)
			(stroke
				(width 0.1)
				(type default)
			)
			(layer "F.Fab")
		)
		(fp_line
			(start -0.12065 0.3048)
			(end -0.67945 0.3048)
			(stroke
				(width 0.1)
				(type default)
			)
			(layer "F.Fab")
		)
		(fp_line
			(start -0.12065 0.2794)
			(end -0.12065 0.3048)
			(stroke
				(width 0.1)
				(type default)
			)
			(layer "F.Fab")
		)
		(fp_line
			(start -0.12065 -0.2794)
			(end 0.12065 -0.2794)
			(stroke
				(width 0.1)
				(type default)
			)
			(layer "F.Fab")
		)
		(fp_line
			(start -0.12065 -0.305054)
			(end -0.12065 -0.2794)
			(stroke
				(width 0.1)
				(type default)
			)
			(layer "F.Fab")
		)
		(fp_line
			(start -0.67945 0.3048)
			(end -0.67945 -0.305054)
			(stroke
				(width 0.1)
				(type default)
			)
			(layer "F.Fab")
		)
		(fp_line
			(start -0.67945 -0.305054)
			(end -0.12065 -0.305054)
			(stroke
				(width 0.1)
				(type default)
			)
			(layer "F.Fab")
		)
		(pad "1" smd circle
			(at -0.40005 0 180)
			(size 0 0)
			(layers "F.Cu" "F.Mask" "F.Paste")
			(net "CLK_50M_BMC_MAC_R")
		)
		(pad "2" smd circle
			(at 0.40005 0 180)
			(size 0 0)
			(layers "F.Cu" "F.Mask" "F.Paste")
			(net "CLK_50M_RMII_BMC_OCP")
		)
	)
	(footprint ""
		(layer "F.Cu")
		(at 152.316434 -110.731046)
		(property "Reference" "U92"
			(at -5.426202 -1.786636 0)
			(unlocked yes)
			(layer "F.SilkS")
			(effects
				(font
					(size 0.7874 0.5842)
					(thickness 0.1524)
				)
				(justify left)
			)
		)
		(property "Value" ""
			(at 0 0 0)
			(layer "F.Fab")
			(effects
				(font
					(size 1.27 1.27)
				)
			)
		)
		(duplicate_pad_numbers_are_jumpers no)
		(fp_line
			(start -2.0574 -1.651)
			(end -0.381 -1.651)
			(stroke
				(width 0.1524)
				(type default)
			)
			(layer "F.SilkS")
		)
		(fp_line
			(start -2.0574 1.651)
			(end -2.0574 -1.651)
			(stroke
				(width 0.1524)
				(type default)
			)
			(layer "F.SilkS")
		)
		(fp_line
			(start -0.381 -1.651)
			(end 0 -1.016)
			(stroke
				(width 0.1524)
				(type default)
			)
			(layer "F.SilkS")
		)
		(fp_line
			(start 0 -1.016)
			(end 0.381 -1.651)
			(stroke
				(width 0.1524)
				(type default)
			)
			(layer "F.SilkS")
		)
		(fp_line
			(start 0.381 -1.651)
			(end 2.0574 -1.651)
			(stroke
				(width 0.1524)
				(type default)
			)
			(layer "F.SilkS")
		)
		(fp_line
			(start 2.0574 -1.651)
			(end 2.0574 1.651)
			(stroke
				(width 0.1524)
				(type default)
			)
			(layer "F.SilkS")
		)
		(fp_line
			(start 2.0574 1.651)
			(end -2.0574 1.651)
			(stroke
				(width 0.1524)
				(type default)
			)
			(layer "F.SilkS")
		)
		(fp_poly
			(pts
				(xy -2.159 -1.016) (xy -2.71272 -0.719328) (xy -2.71272 -1.344168)
			)
			(stroke
				(width 0)
				(type default)
			)
			(fill yes)
			(layer "F.SilkS")
		)
		(fp_line
			(start -1.599946 -1.199896)
			(end -0.899922 -1.199896)
			(stroke
				(width 0.1)
				(type default)
			)
			(layer "F.Fab")
		)
		(fp_line
			(start -1.599946 1.199896)
			(end -1.599946 -1.199896)
			(stroke
				(width 0.1)
				(type default)
			)
			(layer "F.Fab")
		)
		(fp_line
			(start -0.899922 -1.549908)
			(end 0.899922 -1.549908)
			(stroke
				(width 0.1)
				(type default)
			)
			(layer "F.Fab")
		)
		(fp_line
			(start -0.899922 -1.199896)
			(end -0.899922 -1.549908)
			(stroke
				(width 0.1)
				(type default)
			)
			(layer "F.Fab")
		)
		(fp_line
			(start -0.899922 1.199896)
			(end -1.599946 1.199896)
			(stroke
				(width 0.1)
				(type default)
			)
			(layer "F.Fab")
		)
		(fp_line
			(start -0.899922 1.549908)
			(end -0.899922 1.199896)
			(stroke
				(width 0.1)
				(type default)
			)
			(layer "F.Fab")
		)
		(fp_line
			(start 0.899922 -1.549908)
			(end 0.899922 -1.199896)
			(stroke
				(width 0.1)
				(type default)
			)
			(layer "F.Fab")
		)
		(fp_line
			(start 0.899922 -1.199896)
			(end 1.599946 -1.199896)
			(stroke
				(width 0.1)
				(type default)
			)
			(layer "F.Fab")
		)
		(fp_line
			(start 0.899922 1.199896)
			(end 0.899922 1.549908)
			(stroke
				(width 0.1)
				(type default)
			)
			(layer "F.Fab")
		)
		(fp_line
			(start 0.899922 1.549908)
			(end -0.899922 1.549908)
			(stroke
				(width 0.1)
				(type default)
			)
			(layer "F.Fab")
		)
		(fp_line
			(start 1.599946 -1.199896)
			(end 1.599946 1.199896)
			(stroke
				(width 0.1)
				(type default)
			)
			(layer "F.Fab")
		)
		(fp_line
			(start 1.599946 1.199896)
			(end 0.899922 1.199896)
			(stroke
				(width 0.1)
				(type default)
			)
			(layer "F.Fab")
		)
		(fp_poly
			(pts
				(xy -2.71272 -0.719328) (xy -2.71272 -1.344168) (xy -2.159 -1.016)
			)
			(stroke
				(width 0)
				(type default)
			)
			(fill yes)
			(layer "F.Fab")
		)
		(pad "1" smd rect
			(at -1.225042 -0.94996 270)
			(size 0.5588 1.3462)
			(layers "F.Cu" "F.Mask" "F.Paste")
			(net "Net_10730")
		)
		(pad "2" smd rect
			(at -1.225042 0 270)
			(size 0.5588 1.3462)
			(layers "F.Cu" "F.Mask" "F.Paste")
			(net "SCM_IRQ_1V8_N")
		)
		(pad "3" smd rect
			(at -1.225042 0.94996 270)
			(size 0.5588 1.3462)
			(layers "F.Cu" "F.Mask" "F.Paste")
			(net "GND")
		)
		(pad "4" smd rect
			(at 1.225042 0.94996 270)
			(size 0.5588 1.3462)
			(layers "F.Cu" "F.Mask" "F.Paste")
			(net "SCM_IRQ_R_N")
		)
		(pad "5" smd rect
			(at 1.225042 -0.94996 270)
			(size 0.5588 1.3462)
			(layers "F.Cu" "F.Mask" "F.Paste")
			(net "P1V8_AUX")
		)
	)
	(footprint ""
		(layer "F.Cu")
		(at 97.640902 -370.57203 -90)
		(property "Reference" "C717"
			(at 0 0 270)
			(layer "F.SilkS")
			(hide yes)
			(effects
				(font
					(size 1.27 1.27)
				)
			)
		)
		(property "Value" ""
			(at 0 0 270)
			(layer "F.Fab")
			(effects
				(font
					(size 1.27 1.27)
				)
			)
		)
		(duplicate_pad_numbers_are_jumpers no)
		(fp_line
			(start -0.299974 0.150114)
			(end -0.299974 -0.150114)
			(stroke
				(width 0.1)
				(type default)
			)
			(layer "F.Fab")
		)
		(fp_line
			(start 0.299974 0.150114)
			(end -0.299974 0.150114)
			(stroke
				(width 0.1)
				(type default)
			)
			(layer "F.Fab")
		)
		(fp_line
			(start -0.299974 -0.150114)
			(end 0.299974 -0.150114)
			(stroke
				(width 0.1)
				(type default)
			)
			(layer "F.Fab")
		)
		(fp_line
			(start 0.299974 -0.150114)
			(end 0.299974 0.150114)
			(stroke
				(width 0.1)
				(type default)
			)
			(layer "F.Fab")
		)
		(pad "1" smd rect
			(at -0.2667 0 270)
			(size 0.3048 0.381)
			(layers "F.Cu" "F.Mask" "F.Paste")
			(net "P5E_CPU1_P1_TX_C_DP<12>")
		)
		(pad "2" smd rect
			(at 0.2667 0 270)
			(size 0.3048 0.381)
			(layers "F.Cu" "F.Mask" "F.Paste")
			(net "P5E_CPU1_P1_TX_DP<12>")
		)
	)
	(footprint ""
		(layer "F.Cu")
		(at 76.250546 -394.903452 90)
		(property "Reference" "R732"
			(at 0 0 90)
			(layer "F.SilkS")
			(hide yes)
			(effects
				(font
					(size 1.27 1.27)
				)
			)
		)
		(property "Value" ""
			(at 0 0 90)
			(layer "F.Fab")
			(effects
				(font
					(size 1.27 1.27)
				)
			)
		)
		(duplicate_pad_numbers_are_jumpers no)
		(fp_line
			(start 0.32512 -0.175006)
			(end 0.32512 0.175006)
			(stroke
				(width 0.1)
				(type default)
			)
			(layer "F.Fab")
		)
		(fp_line
			(start -0.32512 -0.175006)
			(end 0.32512 -0.175006)
			(stroke
				(width 0.1)
				(type default)
			)
			(layer "F.Fab")
		)
		(fp_line
			(start 0.32512 0.175006)
			(end -0.32512 0.175006)
			(stroke
				(width 0.1)
				(type default)
			)
			(layer "F.Fab")
		)
		(fp_line
			(start -0.32512 0.175006)
			(end -0.32512 -0.175006)
			(stroke
				(width 0.1)
				(type default)
			)
			(layer "F.Fab")
		)
		(pad "1" smd rect
			(at -0.2667 0 90)
			(size 0.3048 0.381)
			(layers "F.Cu" "F.Mask" "F.Paste")
			(net "RST_RT_CPU1_P1_RESET_N")
		)
		(pad "2" smd rect
			(at 0.2667 0 270)
			(size 0.3048 0.381)
			(layers "F.Cu" "F.Mask" "F.Paste")
			(net "RST_RT_CPU1_P1_RESET_R_N")
		)
	)
)
